FILE_TYPE = MACRO_DRAWING;
SET COLOR_WIRE YELLOW;
SET COLOR_PROP ORANGE;
SET COLOR_DOT WHITE;
SET COLOR_ARC YELLOW;
SET COLOR_BODY GREEN;
SET COLOR_NOTE PURPLE;
SET PROP_DISPLAY VALUE;
SET PAGE_NUMBER P159;
FORCEADD QUANTA_TITLE_BLOCK_C..1
(25 275);
FORCEPROP 1 LAST CUSTOM_TXT_CDS <NAME_2>
J 0
(-3150 325);
FORCEPROP 1 LAST CUSTOM_TXT_CDS <NAME_1>
J 0
(-3150 450);
FORCEPROP 1 LAST Q_TITLE Blank
J 0
(-9341 301);
DISPLAY 2.446809 (-9341 301);
PAINT GREEN (-9341 301);
FORCEPROP 2 LAST CUSTOM_TXT_CDS <Q_PROJ>
J 0
(-2357 377);
DISPLAY 1.212766 (-2357 377);
FORCEPROP 2 LAST CUSTOM_TXT_CDS <Q_NUMBER>
J 0
(-1378 378);
DISPLAY 1.212766 (-1378 378);
FORCEPROP 2 LAST CUSTOM_TXT_CDS <Q_REV>
J 0
(-159 378);
DISPLAY 1.212766 (-159 378);
FORCEPROP 2 LAST CUSTOM_TXT_CDS <CON_PAGE_NUM> OF <CON_TOTAL_PAGES>
J 0
(-421 293);
DISPLAY 0.978723 (-421 293);
FORCEPROP 2 LAST CUSTOM_TXT_CDS <CON_LAST_MODIFIED>
J 0
(-1860 290);
DISPLAY 0.978723 (-1860 290);
FORCEPROP 1 LAST CDS_LMAN_SYM_OUTLINE -9475,6775,100,-125
J 0
(25 275);
DISPLAY 0.468085 (25 275);
PAINT GREEN (25 275);
DISPLAY INVISIBLE (25 275);
FORCEPROP 2 LAST CDS_LIB pure_quanta
J 0
(25 275);
PAINT MONO (25 275);
DISPLAY INVISIBLE (25 275);
FORCEPROP 2 LAST PAGE_BORDER TRUE
J 0
(-7865 5525);
DISPLAY 0.638298 (-7865 5525);
PAINT PINK (-7865 5525);
DISPLAY INVISIBLE (-7865 5525);
FORCEPROP 2 LAST CDS_XR_PAGE_TITLE CR-181 : @T6G_MB_LIB.T6G(SCH_1):PAGE181
J 0
(-7865 5525);
DISPLAY 0.638298 (-7865 5525);
PAINT PINK (-7865 5525);
DISPLAY INVISIBLE (-7865 5525);
FORCEPROP 2 LAST CUSTOM_TXT_CDS <XR_PAGE_TITLE>
J 0
(-7865 5525);
DISPLAY 0.638298 (-7865 5525);
PAINT PINK (-7865 5525);
DISPLAY INVISIBLE (-7865 5525);
FORCEPROP 1 LAST COMMENT_BODY TRUE
J 0
(37 262);
DISPLAY 0.978723 (37 262);
PAINT GREEN (37 262);
DISPLAY INVISIBLE (37 262);
FORCEPROP 1 LAST Q_DEPT BU9
J 1
(-3738 324);
DISPLAY 1.957447 (-3738 324);
PAINT GREEN (-3738 324);
DISPLAY INVISIBLE (-3738 324);
FORCEPROP 0 LAST CDS_CON_LAST_MODIFIED Thu Aug 24 10:14:58 2023
J 0
(-1860 290);
PAINT MONO (-1860 290);
DISPLAY INVISIBLE (-1860 290);
QUIT
